FILE_TYPE = CONNECTIVITY;
{Allegro Design Entry HDL 17.4-2019 S026 (4007227) 1/17/2022}
"PAGE_NUMBER" = 376;
0"NC";
1"GND\g";
2"GND\g";
3"GND\g";
4"GND\g";
5"GND\g";
6"GND\g";
7"GND\g";
8"GND\g";
9"GND\g";
10"GND\g";
11"GND\g";
12"GND\g";
13"GND\g";
14"GND\g";
15"GND\g";
16"GND\g";
17"SMB_RT_CPU1_P0_ROM_MUX_2D_SDA";
18"P3V3_AUX\g";
19"SMB_RT_CPU1_P0_ROM_MUX_2D_SCL";
20"SMB_RT_CPU1_P0_ROM_MUX_1D_SDA";
21"SMB_RT_CPU1_P0_ROM_MUX_1D_SCL";
22"RST_SMB_RT_ROM_R1_N";
23"RST_SMB_RT_ROM_R1_N";
24"RST_SMB_RT_ROM_R1_N";
25"RST_SMB_RT_ROM_R1_N";
26"RST_SMB_RT_ROM_R1_N";
27"RST_SMB_RT_ROM_R1_N";
28"RST_SMB_RT_ROM_R1_N";
29"RST_SMB_RT_ROM_R1_N";
30"SMB_RT_CPU1_P2_ROM_MUX_2D_SCL";
31"SMB_RT_CPU1_P0_ROM_R_SCL";
32"SMB_RT_CPU1_P0_ROM_R_SDA";
33"FM_SMB_RT_ROM_MUX1_SEL";
34"RT_ROM_MUX1_OE_N";
35"SMB_RT_CPU1_P1_ROM_R_SCL";
36"SMB_RT_CPU1_P1_ROM_R_SDA";
37"SMB_RT_CPU1_P1_ROM_MUX_2D_SCL";
38"SMB_RT_CPU1_P1_ROM_MUX_2D_SDA";
39"SMB_RT_CPU1_P1_ROM_MUX_1D_SDA";
40"SMB_RT_CPU1_P3_ROM_R_SCL";
41"FM_SMB_RT_ROM_MUX3_SEL";
42"RT_ROM_MUX3_OE_N";
43"SMB_RT_CPU1_P3_ROM_MUX_1D_SCL";
44"SMB_RT_CPU1_P3_ROM_MUX_1D_SDA";
45"SMB_RT_CPU1_P3_ROM_MUX_2D_SCL";
46"SMB_RT_CPU1_P3_ROM_MUX_2D_SDA";
47"RT_ROM_MUX4_OE_N";
48"FM_SMB_RT_ROM_MUX4_SEL";
49"SMB_RT_CPU1_P2_ROM_MUX_1D_SCL";
50"SMB_RT_CPU1_P2_ROM_MUX_1D_SDA";
51"SMB_RT_CPU1_P2_ROM_MUX_2D_SDA";
52"SMB_RT_CPU1_P2_ROM_R_SDA";
53"SMB_RT_CPU1_P2_ROM_R_SCL";
54"RT_ROM_MUX2_OE_N";
55"FM_SMB_RT_ROM_MUX2_SEL";
56"SMB_RT_CPU1_P1_ROM_MUX_1D_SCL";
57"SMB_RT_CPU1_P3_ROM_R_SDA";
58"SMB_RT_CPU0_P0_ROM_MUX_1D_SCL";
59"RT_ROM_MUX5_OE_N";
60"FM_SMB_RT_ROM_MUX5_SEL";
61"SMB_RT_CPU0_P0_ROM_MUX_1D_SDA";
62"SMB_RT_CPU0_P0_ROM_MUX_2D_SCL";
63"SMB_RT_CPU0_P0_ROM_MUX_2D_SDA";
64"SMB_RT_CPU0_P0_ROM_R_SCL";
65"SMB_RT_CPU0_P0_ROM_R_SDA";
66"GND\g";
67"P3V3_AUX\g";
68"P3V3_AUX\g";
69"GND\g";
70"P3V3_AUX\g";
71"GND\g";
72"P3V3_AUX\g";
73"GND\g";
74"P3V3_AUX\g";
75"P3V3_AUX\g";
76"GND\g";
77"RT_ROM_MUX6_OE_N";
78"FM_SMB_RT_ROM_MUX6_SEL";
79"SMB_RT_CPU0_P1_ROM_MUX_1D_SDA";
80"SMB_RT_CPU0_P1_ROM_MUX_1D_SCL";
81"GND\g";
82"SMB_RT_CPU0_P1_ROM_R_SCL";
83"SMB_RT_CPU0_P1_ROM_MUX_2D_SDA";
84"SMB_RT_CPU0_P1_ROM_MUX_2D_SCL";
85"SMB_RT_CPU0_P1_ROM_R_SDA";
86"RT_ROM_MUX7_OE_N";
87"FM_SMB_RT_ROM_MUX7_SEL";
88"SMB_RT_CPU0_P3_ROM_MUX_1D_SDA";
89"SMB_RT_CPU0_P3_ROM_MUX_2D_SCL";
90"SMB_RT_CPU0_P3_ROM_MUX_2D_SDA";
91"GND\g";
92"SMB_RT_CPU0_P3_ROM_R_SDA";
93"SMB_RT_CPU0_P3_ROM_R_SCL";
94"SMB_RT_CPU0_P2_ROM_MUX_1D_SDA";
95"SMB_RT_CPU0_P2_ROM_MUX_2D_SCL";
96"SMB_RT_CPU0_P2_ROM_MUX_1D_SCL";
97"FM_SMB_RT_ROM_MUX8_SEL";
98"RT_ROM_MUX8_OE_N";
99"P3V3_AUX\g";
100"SMB_RT_CPU0_P2_ROM_R_SDA";
101"SMB_RT_CPU0_P2_ROM_R_SCL";
102"GND\g";
103"SMB_RT_CPU0_P2_ROM_MUX_2D_SDA";
104"SMB_RT_CPU0_P3_ROM_MUX_1D_SCL";
%"UNIVERSAL_GND"
"1","(-5750,5325)","0","pure_quanta_power","I10";
;
CDS_LIB"pure_quanta_power"
HDL_POWER"GND";
"A"76;
%"UNIVERSAL_POWER"
"1","(-1350,2825)","0","pure_quanta_power","I100";
;
HDL_POWER"P3V3_AUX"
CDS_LIB"pure_quanta_power";
"A"75;
%"UNIVERSAL_POWER"
"1","(-1325,1400)","0","pure_quanta_power","I103";
;
HDL_POWER"P3V3_AUX"
CDS_LIB"pure_quanta_power";
"A"99;
%"UNIVERSAL_GND"
"1","(-1500,1800)","0","pure_quanta_power","I104";
;
CDS_LIB"pure_quanta_power"
HDL_POWER"GND";
"A"91;
%"Q_CAP"
"1","(-1175,1125)","0","pure_quanta","I105";
;
LOCATION"C1071"
$SEC"1"
CDS_SEC"1"
VALUE"0.1UF"
VOLTAGE"10V"
PACK_TYPE"C0201"
TOLERANCE"10%"
MATERIAL"X7S"
CDS_LIB"pure_quanta"
PART_NUMBER"CH4102K6E00";
"B"
$PN"2"1;
"A"
$PN"1"99;
%"UNIVERSAL_GND"
"1","(-1175,925)","0","pure_quanta_power","I106";
;
CDS_LIB"pure_quanta_power"
HDL_POWER"GND";
"A"1;
%"UNIVERSAL_GND"
"1","(-1475,375)","0","pure_quanta_power","I107";
;
CDS_LIB"pure_quanta_power"
HDL_POWER"GND";
"A"102;
%"PI3CSW12ZUAEX"
"1","(-1900,2100)","0","pure_quanta","I108";
;
LOCATION"U46"
$SEC"1"
CDS_SEC"1"
MATERIAL"IC"
VALUE"PI3CSW12ZUAEX"
PART_TYPE"SMLF"
CDS_LIB"pure_quanta"
CDS_LMAN_SYM_OUTLINE"-150,200,150,-200"
NEEDS_NO_SIZE"TRUE"
PART_NUMBER"AL3CSW12000";
"D+"
$PN"8"93;
"GND"
$PN"5"91;
"1D-"
$PN"2"88;
"VDD"
$PN"10"75;
"S"
$PN"9"87;
"OE# \B"
$PN"6"86;
"D-"
$PN"7"92;
"2D-"
$PN"4"90;
"2D+"
$PN"3"89;
"1D+"
$PN"1"104;
%"Q_RES"
"1","(-3100,3675)","0","pure_quanta","I109";
;
LOCATION"R1210"
$SEC"1"
CDS_SEC"1"
VALUE"0"
PACK_TYPE"0201LF"
MATERIAL"CHIP"
TOLERANCE"5%"
WATTAGE"1/20W"
CDS_LIB"pure_quanta"
PART_NUMBER"CS00001JE10";
"B"
$PN"2"78;
"A"
$PN"1"23;
%"Q_RES"
"1","(-3100,3725)","0","pure_quanta","I110";
;
LOCATION"R1218"
$SEC"1"
CDS_SEC"1"
VALUE"1K"
PACK_TYPE"0201LF"
MATERIAL"CHIP"
CDS_LIB"pure_quanta"
TOLERANCE"1%"
WATTAGE"1/20W"
PART_NUMBER"CS21001FE07";
"B"
$PN"2"77;
"A"
$PN"1"3;
%"Q_RES"
"1","(-3150,2200)","0","pure_quanta","I115";
;
LOCATION"R1206"
$SEC"1"
CDS_SEC"1"
PACK_TYPE"0201LF"
MATERIAL"CHIP"
VALUE"0"
TOLERANCE"5%"
WATTAGE"1/20W"
CDS_LIB"pure_quanta"
PART_NUMBER"CS00001JE10";
"B"
$PN"2"87;
"A"
$PN"1"27;
%"Q_RES"
"1","(-3150,2250)","0","pure_quanta","I116";
;
LOCATION"R1216"
$SEC"1"
CDS_SEC"1"
PACK_TYPE"0201LF"
MATERIAL"CHIP"
VALUE"1K"
CDS_LIB"pure_quanta"
TOLERANCE"1%"
WATTAGE"1/20W"
PART_NUMBER"CS21001FE07";
"B"
$PN"2"86;
"A"
$PN"1"4;
%"PI3CSW12ZUAEX"
"1","(-1875,675)","0","pure_quanta","I121";
;
LOCATION"U47"
$SEC"1"
CDS_SEC"1"
MATERIAL"IC"
PART_TYPE"SMLF"
VALUE"PI3CSW12ZUAEX"
NEEDS_NO_SIZE"TRUE"
CDS_LMAN_SYM_OUTLINE"-150,200,150,-200"
CDS_LIB"pure_quanta"
PART_NUMBER"AL3CSW12000";
"D+"
$PN"8"101;
"GND"
$PN"5"102;
"1D-"
$PN"2"94;
"VDD"
$PN"10"99;
"S"
$PN"9"97;
"OE# \B"
$PN"6"98;
"D-"
$PN"7"100;
"2D-"
$PN"4"103;
"2D+"
$PN"3"95;
"1D+"
$PN"1"96;
%"Q_RES"
"1","(-3125,825)","0","pure_quanta","I122";
;
LOCATION"R1217"
$SEC"1"
CDS_SEC"1"
PACK_TYPE"0201LF"
MATERIAL"CHIP"
VALUE"1K"
CDS_LIB"pure_quanta"
TOLERANCE"1%"
WATTAGE"1/20W"
PART_NUMBER"CS21001FE07";
"B"
$PN"2"98;
"A"
$PN"1"5;
%"Q_RES"
"1","(-3125,775)","0","pure_quanta","I123";
;
LOCATION"R1209"
$SEC"1"
CDS_SEC"1"
VALUE"0"
MATERIAL"CHIP"
PACK_TYPE"0201LF"
CDS_LIB"pure_quanta"
WATTAGE"1/20W"
TOLERANCE"5%"
PART_NUMBER"CS00001JE10";
"B"
$PN"2"97;
"A"
$PN"1"28;
%"UNIVERSAL_GND"
"1","(-4225,5250)","5","pure_quanta_power","I128";
;
CDS_LIB"pure_quanta_power"
HDL_POWER"GND";
"A"2;
%"UNIVERSAL_GND"
"1","(-4300,3725)","5","pure_quanta_power","I130";
;
CDS_LIB"pure_quanta_power"
HDL_POWER"GND";
"A"3;
%"UNIVERSAL_GND"
"1","(-4350,2250)","5","pure_quanta_power","I132";
;
CDS_LIB"pure_quanta_power"
HDL_POWER"GND";
"A"4;
%"UNIVERSAL_GND"
"1","(-4325,825)","5","pure_quanta_power","I134";
;
CDS_LIB"pure_quanta_power"
HDL_POWER"GND";
"A"5;
%"PI3CSW12ZUAEX"
"1","(-6150,5625)","0","pure_quanta","I22";
;
LOCATION"U45"
$SEC"1"
CDS_SEC"1"
PART_TYPE"SMLF"
VALUE"PI3CSW12ZUAEX"
MATERIAL"IC"
CDS_LIB"pure_quanta"
CDS_LMAN_SYM_OUTLINE"-150,200,150,-200"
NEEDS_NO_SIZE"TRUE"
PART_NUMBER"AL3CSW12000";
"D+"
$PN"8"31;
"GND"
$PN"5"76;
"1D-"
$PN"2"20;
"VDD"
$PN"10"18;
"S"
$PN"9"33;
"OE# \B"
$PN"6"34;
"D-"
$PN"7"32;
"2D-"
$PN"4"17;
"2D+"
$PN"3"19;
"1D+"
$PN"1"21;
%"UNIVERSAL_POWER"
"1","(-5600,6350)","0","pure_quanta_power","I23";
;
HDL_POWER"P3V3_AUX"
CDS_LIB"pure_quanta_power";
"A"18;
%"Q_CAP"
"1","(-5450,6075)","0","pure_quanta","I24";
;
LOCATION"C1069"
$SEC"1"
CDS_SEC"1"
MATERIAL"X7S"
PACK_TYPE"C0201"
TOLERANCE"10%"
VALUE"0.1UF"
VOLTAGE"10V"
CDS_LIB"pure_quanta"
PART_NUMBER"CH4102K6E00";
"B"
$PN"2"6;
"A"
$PN"1"18;
%"UNIVERSAL_GND"
"1","(-5450,5875)","0","pure_quanta_power","I25";
;
CDS_LIB"pure_quanta_power"
HDL_POWER"GND";
"A"6;
%"Q_RES"
"1","(-7400,5775)","0","pure_quanta","I28";
;
LOCATION"R1215"
$SEC"1"
CDS_SEC"1"
PACK_TYPE"0201LF"
MATERIAL"CHIP"
VALUE"1K"
CDS_LIB"pure_quanta"
TOLERANCE"1%"
WATTAGE"1/20W"
PART_NUMBER"CS21001FE07";
"B"
$PN"2"34;
"A"
$PN"1"7;
%"UNIVERSAL_GND"
"1","(-8600,5775)","5","pure_quanta_power","I29";
;
CDS_LIB"pure_quanta_power"
HDL_POWER"GND";
"A"7;
%"Q_RES"
"1","(-7400,5725)","0","pure_quanta","I30";
;
LOCATION"R1201"
$SEC"1"
CDS_SEC"1"
PACK_TYPE"0201LF"
MATERIAL"CHIP"
VALUE"0"
TOLERANCE"5%"
WATTAGE"1/20W"
CDS_LIB"pure_quanta"
PART_NUMBER"CS00001JE10";
"B"
$PN"2"33;
"A"
$PN"1"22;
%"PI3CSW12ZUAEX"
"1","(-6225,4200)","0","pure_quanta","I31";
;
LOCATION"U42"
$SEC"1"
CDS_SEC"1"
PART_TYPE"SMLF"
MATERIAL"IC"
VALUE"PI3CSW12ZUAEX"
CDS_LIB"pure_quanta"
CDS_LMAN_SYM_OUTLINE"-150,200,150,-200"
NEEDS_NO_SIZE"TRUE"
PART_NUMBER"AL3CSW12000";
"D+"
$PN"8"35;
"GND"
$PN"5"73;
"1D-"
$PN"2"39;
"VDD"
$PN"10"74;
"S"
$PN"9"55;
"OE# \B"
$PN"6"54;
"D-"
$PN"7"36;
"2D-"
$PN"4"38;
"2D+"
$PN"3"37;
"1D+"
$PN"1"56;
%"UNIVERSAL_GND"
"1","(-5525,4450)","0","pure_quanta_power","I36";
;
CDS_LIB"pure_quanta_power"
HDL_POWER"GND";
"A"8;
%"Q_CAP"
"1","(-5525,4650)","0","pure_quanta","I37";
;
LOCATION"C1067"
$SEC"1"
CDS_SEC"1"
MATERIAL"X7S"
PACK_TYPE"C0201"
TOLERANCE"10%"
VOLTAGE"10V"
VALUE"0.1UF"
CDS_LIB"pure_quanta"
PART_NUMBER"CH4102K6E00";
"B"
$PN"2"8;
"A"
$PN"1"74;
%"UNIVERSAL_POWER"
"1","(-5675,4925)","0","pure_quanta_power","I38";
;
HDL_POWER"P3V3_AUX"
CDS_LIB"pure_quanta_power";
"A"74;
%"UNIVERSAL_GND"
"1","(-5825,3900)","0","pure_quanta_power","I39";
;
CDS_LIB"pure_quanta_power"
HDL_POWER"GND";
"A"73;
%"Q_RES"
"1","(-7475,4300)","0","pure_quanta","I40";
;
LOCATION"R1199"
$SEC"1"
CDS_SEC"1"
PACK_TYPE"0201LF"
MATERIAL"CHIP"
VALUE"0"
TOLERANCE"5%"
WATTAGE"1/20W"
CDS_LIB"pure_quanta"
PART_NUMBER"CS00001JE10";
"B"
$PN"2"55;
"A"
$PN"1"24;
%"Q_RES"
"1","(-7475,4350)","0","pure_quanta","I41";
;
LOCATION"R1213"
$SEC"1"
CDS_SEC"1"
PACK_TYPE"0201LF"
MATERIAL"CHIP"
VALUE"1K"
CDS_LIB"pure_quanta"
TOLERANCE"1%"
WATTAGE"1/20W"
PART_NUMBER"CS21001FE07";
"B"
$PN"2"54;
"A"
$PN"1"9;
%"UNIVERSAL_GND"
"1","(-8675,4350)","5","pure_quanta_power","I44";
;
CDS_LIB"pure_quanta_power"
HDL_POWER"GND";
"A"9;
%"PI3CSW12ZUAEX"
"1","(-6275,2725)","0","pure_quanta","I46";
;
LOCATION"U41"
$SEC"1"
CDS_SEC"1"
PART_TYPE"SMLF"
VALUE"PI3CSW12ZUAEX"
MATERIAL"IC"
NEEDS_NO_SIZE"TRUE"
CDS_LMAN_SYM_OUTLINE"-150,200,150,-200"
CDS_LIB"pure_quanta"
PART_NUMBER"AL3CSW12000";
"D+"
$PN"8"40;
"GND"
$PN"5"71;
"1D-"
$PN"2"44;
"VDD"
$PN"10"72;
"S"
$PN"9"41;
"OE# \B"
$PN"6"42;
"D-"
$PN"7"57;
"2D-"
$PN"4"46;
"2D+"
$PN"3"45;
"1D+"
$PN"1"43;
%"UNIVERSAL_POWER"
"1","(-5725,3450)","0","pure_quanta_power","I47";
;
HDL_POWER"P3V3_AUX"
CDS_LIB"pure_quanta_power";
"A"72;
%"Q_CAP"
"1","(-5575,3175)","0","pure_quanta","I48";
;
LOCATION"C1066"
$SEC"1"
CDS_SEC"1"
VALUE"0.1UF"
VOLTAGE"10V"
PACK_TYPE"C0201"
TOLERANCE"10%"
MATERIAL"X7S"
CDS_LIB"pure_quanta"
PART_NUMBER"CH4102K6E00";
"B"
$PN"2"10;
"A"
$PN"1"72;
%"UNIVERSAL_GND"
"1","(-5575,2975)","0","pure_quanta_power","I51";
;
CDS_LIB"pure_quanta_power"
HDL_POWER"GND";
"A"10;
%"UNIVERSAL_GND"
"1","(-5875,2425)","0","pure_quanta_power","I52";
;
CDS_LIB"pure_quanta_power"
HDL_POWER"GND";
"A"71;
%"Q_RES"
"1","(-7525,2825)","0","pure_quanta","I53";
;
LOCATION"R1198"
$SEC"1"
CDS_SEC"1"
VALUE"0"
MATERIAL"CHIP"
PACK_TYPE"0201LF"
CDS_LIB"pure_quanta"
WATTAGE"1/20W"
TOLERANCE"5%"
PART_NUMBER"CS00001JE10";
"B"
$PN"2"41;
"A"
$PN"1"25;
%"Q_RES"
"1","(-7525,2875)","0","pure_quanta","I54";
;
LOCATION"R1212"
$SEC"1"
CDS_SEC"1"
VALUE"1K"
MATERIAL"CHIP"
PACK_TYPE"0201LF"
WATTAGE"1/20W"
TOLERANCE"1%"
CDS_LIB"pure_quanta"
PART_NUMBER"CS21001FE07";
"B"
$PN"2"42;
"A"
$PN"1"11;
%"UNIVERSAL_GND"
"1","(-8725,2875)","5","pure_quanta_power","I59";
;
CDS_LIB"pure_quanta_power"
HDL_POWER"GND";
"A"11;
%"PI3CSW12ZUAEX"
"1","(-6225,1125)","0","pure_quanta","I61";
;
LOCATION"U43"
$SEC"1"
CDS_SEC"1"
PART_TYPE"SMLF"
VALUE"PI3CSW12ZUAEX"
MATERIAL"IC"
NEEDS_NO_SIZE"TRUE"
CDS_LMAN_SYM_OUTLINE"-150,200,150,-200"
CDS_LIB"pure_quanta"
PART_NUMBER"AL3CSW12000";
"D+"
$PN"8"53;
"GND"
$PN"5"69;
"1D-"
$PN"2"50;
"VDD"
$PN"10"70;
"S"
$PN"9"48;
"OE# \B"
$PN"6"47;
"D-"
$PN"7"52;
"2D-"
$PN"4"51;
"2D+"
$PN"3"30;
"1D+"
$PN"1"49;
%"UNIVERSAL_GND"
"1","(-5525,1375)","0","pure_quanta_power","I64";
;
CDS_LIB"pure_quanta_power"
HDL_POWER"GND";
"A"12;
%"Q_CAP"
"1","(-5525,1575)","0","pure_quanta","I65";
;
LOCATION"C1068"
$SEC"1"
CDS_SEC"1"
VALUE"0.1UF"
VOLTAGE"10V"
PACK_TYPE"C0201"
TOLERANCE"10%"
MATERIAL"X7S"
CDS_LIB"pure_quanta"
PART_NUMBER"CH4102K6E00";
"B"
$PN"2"12;
"A"
$PN"1"70;
%"UNIVERSAL_POWER"
"1","(-5675,1850)","0","pure_quanta_power","I66";
;
HDL_POWER"P3V3_AUX"
CDS_LIB"pure_quanta_power";
"A"70;
%"UNIVERSAL_GND"
"1","(-5825,825)","0","pure_quanta_power","I67";
;
CDS_LIB"pure_quanta_power"
HDL_POWER"GND";
"A"69;
%"Q_RES"
"1","(-7475,1225)","0","pure_quanta","I68";
;
LOCATION"R1200"
$SEC"1"
CDS_SEC"1"
VALUE"0"
MATERIAL"CHIP"
PACK_TYPE"0201LF"
CDS_LIB"pure_quanta"
WATTAGE"1/20W"
TOLERANCE"5%"
PART_NUMBER"CS00001JE10";
"B"
$PN"2"48;
"A"
$PN"1"26;
%"Q_RES"
"1","(-7475,1275)","0","pure_quanta","I69";
;
LOCATION"R1214"
$SEC"1"
CDS_SEC"1"
PACK_TYPE"0201LF"
MATERIAL"CHIP"
VALUE"1K"
CDS_LIB"pure_quanta"
TOLERANCE"1%"
WATTAGE"1/20W"
PART_NUMBER"CS21001FE07";
"B"
$PN"2"47;
"A"
$PN"1"13;
%"UNIVERSAL_GND"
"1","(-8675,1275)","5","pure_quanta_power","I74";
;
CDS_LIB"pure_quanta_power"
HDL_POWER"GND";
"A"13;
%"PI3CSW12ZUAEX"
"1","(-1850,3575)","0","pure_quanta","I76";
;
LOCATION"U48"
$SEC"1"
CDS_SEC"1"
PART_TYPE"SMLF"
MATERIAL"IC"
VALUE"PI3CSW12ZUAEX"
CDS_LIB"pure_quanta"
CDS_LMAN_SYM_OUTLINE"-150,200,150,-200"
NEEDS_NO_SIZE"TRUE"
PART_NUMBER"AL3CSW12000";
"D+"
$PN"8"82;
"GND"
$PN"5"81;
"1D-"
$PN"2"79;
"VDD"
$PN"10"67;
"S"
$PN"9"78;
"OE# \B"
$PN"6"77;
"D-"
$PN"7"85;
"2D-"
$PN"4"83;
"2D+"
$PN"3"84;
"1D+"
$PN"1"80;
%"UNIVERSAL_GND"
"1","(-1075,5350)","0","pure_quanta_power","I79";
;
CDS_LIB"pure_quanta_power"
HDL_POWER"GND";
"A"14;
%"Q_CAP"
"1","(-1075,5550)","0","pure_quanta","I80";
;
LOCATION"C1073"
$SEC"1"
CDS_SEC"1"
MATERIAL"X7S"
PACK_TYPE"C0201"
TOLERANCE"10%"
VOLTAGE"10V"
VALUE"0.1UF"
CDS_LIB"pure_quanta"
PART_NUMBER"CH4102K6E00";
"B"
$PN"2"14;
"A"
$PN"1"68;
%"UNIVERSAL_POWER"
"1","(-1225,5825)","0","pure_quanta_power","I81";
;
HDL_POWER"P3V3_AUX"
CDS_LIB"pure_quanta_power";
"A"68;
%"UNIVERSAL_GND"
"1","(-1375,4800)","0","pure_quanta_power","I82";
;
CDS_LIB"pure_quanta_power"
HDL_POWER"GND";
"A"66;
%"UNIVERSAL_POWER"
"1","(-1300,4300)","0","pure_quanta_power","I83";
;
HDL_POWER"P3V3_AUX"
CDS_LIB"pure_quanta_power";
"A"67;
%"Q_CAP"
"1","(-1150,4025)","0","pure_quanta","I84";
;
LOCATION"C1072"
$SEC"1"
CDS_SEC"1"
MATERIAL"X7S"
PACK_TYPE"C0201"
TOLERANCE"10%"
VOLTAGE"10V"
VALUE"0.1UF"
CDS_LIB"pure_quanta"
PART_NUMBER"CH4102K6E00";
"B"
$PN"2"15;
"A"
$PN"1"67;
%"PI3CSW12ZUAEX"
"1","(-1775,5100)","0","pure_quanta","I85";
;
LOCATION"U49"
$SEC"1"
CDS_SEC"1"
PART_TYPE"SMLF"
VALUE"PI3CSW12ZUAEX"
MATERIAL"IC"
CDS_LIB"pure_quanta"
CDS_LMAN_SYM_OUTLINE"-150,200,150,-200"
NEEDS_NO_SIZE"TRUE"
PART_NUMBER"AL3CSW12000";
"D+"
$PN"8"64;
"GND"
$PN"5"66;
"1D-"
$PN"2"61;
"VDD"
$PN"10"68;
"S"
$PN"9"60;
"OE# \B"
$PN"6"59;
"D-"
$PN"7"65;
"2D-"
$PN"4"63;
"2D+"
$PN"3"62;
"1D+"
$PN"1"58;
%"Q_RES"
"1","(-3025,5200)","0","pure_quanta","I86";
;
LOCATION"R1211"
$SEC"1"
CDS_SEC"1"
PACK_TYPE"0201LF"
MATERIAL"CHIP"
VALUE"0"
TOLERANCE"5%"
WATTAGE"1/20W"
CDS_LIB"pure_quanta"
PART_NUMBER"CS00001JE10";
"B"
$PN"2"60;
"A"
$PN"1"29;
%"Q_RES"
"1","(-3025,5250)","0","pure_quanta","I87";
;
LOCATION"R1219"
$SEC"1"
CDS_SEC"1"
PACK_TYPE"0201LF"
MATERIAL"CHIP"
VALUE"1K"
CDS_LIB"pure_quanta"
TOLERANCE"1%"
WATTAGE"1/20W"
PART_NUMBER"CS21001FE07";
"B"
$PN"2"59;
"A"
$PN"1"2;
%"UNIVERSAL_GND"
"1","(-1150,3825)","0","pure_quanta_power","I96";
;
CDS_LIB"pure_quanta_power"
HDL_POWER"GND";
"A"15;
%"UNIVERSAL_GND"
"1","(-1450,3275)","0","pure_quanta_power","I97";
;
CDS_LIB"pure_quanta_power"
HDL_POWER"GND";
"A"81;
%"UNIVERSAL_GND"
"1","(-1200,2350)","0","pure_quanta_power","I98";
;
CDS_LIB"pure_quanta_power"
HDL_POWER"GND";
"A"16;
%"Q_CAP"
"1","(-1200,2550)","0","pure_quanta","I99";
;
LOCATION"C1070"
$SEC"1"
CDS_SEC"1"
MATERIAL"X7S"
TOLERANCE"10%"
PACK_TYPE"C0201"
VOLTAGE"10V"
VALUE"0.1UF"
CDS_LIB"pure_quanta"
PART_NUMBER"CH4102K6E00";
"B"
$PN"2"16;
"A"
$PN"1"75;
END.
